FILE_TYPE = CONNECTIVITY;
{Allegro Design Entry HDL 16.6-p007 (v16-6-112F) 10/10/2012}
"PAGE_NUMBER" = 25;
0"NC";
1"M_C_DQS_DP<17:0>";
2"M_C_MA<17:0>";
3"M_C_DQS_DN<17:0>";
4"M_C_ODT<3:0>";
5"M_C_CS_N<7:0>";
6"M_C_CKE<3:0>";
7"M_C_BG<1:0>";
8"M_C_BA<1:0>";
9"M_C_DQ<63:0>";
10"M_C_ECC<7:0>";
11"M_C_CLK_DP<3:0>";
12"M_C_CLK_DN<3:0>";
13"M_C_DQ<4>";
14"M_C_C<2>";
15"M_C_CLK_DN<3>";
16"M_C_CLK_DN<2>";
17"M_C_CLK_DN<1>";
18"M_C_CLK_DN<0>";
19"M_C_CLK_DP<3>";
20"M_C_CLK_DP<2>";
21"M_C_CLK_DP<1>";
22"M_C_CLK_DP<0>";
23"M_C_DQ<9>";
24"M_C_DQ<8>";
25"M_C_DQ<7>";
26"M_C_DQ<6>";
27"M_C_DQ<5>";
28"M_C_DQ<3>";
29"M_C_DQ<2>";
30"M_C_DQ<1>";
31"M_C_DQ<0>";
32"M_C_ECC<7>";
33"M_C_ECC<6>";
34"M_C_ECC<5>";
35"M_C_ECC<4>";
36"M_C_ECC<3>";
37"M_C_ECC<2>";
38"M_C_ECC<1>";
39"M_C_ECC<0>";
40"M_C_DQ<50>";
41"M_C_DQ<49>";
42"M_C_DQ<48>";
43"M_C_DQ<47>";
44"M_C_DQ<46>";
45"M_C_DQ<45>";
46"M_C_DQ<44>";
47"M_C_DQ<43>";
48"M_C_DQ<42>";
49"M_C_DQ<41>";
50"M_C_DQ<40>";
51"M_C_DQ<39>";
52"M_C_DQ<38>";
53"M_C_DQ<37>";
54"M_C_DQ<36>";
55"M_C_DQ<35>";
56"M_C_DQ<34>";
57"M_C_DQ<33>";
58"M_C_DQ<32>";
59"M_C_DQ<31>";
60"M_C_DQ<30>";
61"M_C_DQ<29>";
62"M_C_DQ<28>";
63"M_C_DQ<27>";
64"M_C_DQ<26>";
65"M_C_DQ<25>";
66"M_C_DQ<24>";
67"M_C_DQ<23>";
68"M_C_DQ<22>";
69"M_C_DQ<20>";
70"M_C_DQ<19>";
71"M_C_DQ<18>";
72"M_C_DQ<17>";
73"M_C_DQ<16>";
74"M_C_DQ<15>";
75"M_C_DQ<14>";
76"M_C_DQ<13>";
77"M_C_DQ<12>";
78"M_C_DQ<11>";
79"M_C_DQ<10>";
80"M_C_DQ<21>";
81"M_C_DQ<63>";
82"M_C_DQ<62>";
83"M_C_DQ<61>";
84"M_C_DQ<60>";
85"M_C_DQ<59>";
86"M_C_DQ<58>";
87"M_C_DQ<57>";
88"M_C_DQ<56>";
89"M_C_DQ<55>";
90"M_C_DQ<54>";
91"M_C_DQ<53>";
92"M_C_DQ<52>";
93"M_C_DQ<51>";
94"M_C_BA<1>";
95"M_C_BA<0>";
96"M_C_BG<1>";
97"M_C_BG<0>";
98"M_C_CKE<3>";
99"M_C_CKE<2>";
100"M_C_CKE<1>";
101"M_C_CKE<0>";
102"M_C_CS_N<7>";
103"M_C_CS_N<6>";
104"M_C_CS_N<5>";
105"M_C_CS_N<4>";
106"M_C_CS_N<3>";
107"M_C_CS_N<2>";
108"M_C_CS_N<1>";
109"M_C_CS_N<0>";
110"M_C_MA<1>";
111"M_C_MA<0>";
112"M_C_ODT<3>";
113"M_C_ODT<2>";
114"M_C_ODT<1>";
115"M_C_ODT<0>";
116"M_C_PAR";
117"M_C_ACT_N";
118"M_C_ALERT_N";
119"M_C_DQS_DN<17>";
120"M_C_DQS_DN<16>";
121"M_C_DQS_DN<15>";
122"M_C_DQS_DN<14>";
123"M_C_DQS_DN<13>";
124"M_C_DQS_DN<12>";
125"M_C_DQS_DN<11>";
126"M_C_DQS_DN<10>";
127"M_C_DQS_DN<9>";
128"M_C_DQS_DN<8>";
129"M_C_DQS_DN<7>";
130"M_C_DQS_DN<6>";
131"M_C_DQS_DN<5>";
132"M_C_DQS_DN<4>";
133"M_C_DQS_DN<3>";
134"M_C_DQS_DN<2>";
135"M_C_DQS_DN<1>";
136"M_C_DQS_DN<0>";
137"M_C_DQS_DP<4>";
138"M_C_DQS_DP<3>";
139"M_C_DQS_DP<2>";
140"M_C_DQS_DP<1>";
141"M_C_DQS_DP<0>";
142"M_C_MA<17>";
143"M_C_MA<16>";
144"M_C_MA<15>";
145"M_C_MA<14>";
146"M_C_MA<13>";
147"M_C_MA<12>";
148"M_C_MA<11>";
149"M_C_MA<10>";
150"M_C_MA<9>";
151"M_C_MA<8>";
152"M_C_MA<7>";
153"M_C_MA<6>";
154"M_C_MA<5>";
155"M_C_MA<4>";
156"M_C_MA<3>";
157"M_C_MA<2>";
158"M_C_DQS_DP<17>";
159"M_C_DQS_DP<16>";
160"M_C_DQS_DP<15>";
161"M_C_DQS_DP<14>";
162"M_C_DQS_DP<13>";
163"M_C_DQS_DP<12>";
164"M_C_DQS_DP<11>";
165"M_C_DQS_DP<10>";
166"M_C_DQS_DP<9>";
167"M_C_DQS_DP<8>";
168"M_C_DQS_DP<7>";
169"M_C_DQS_DP<6>";
170"M_C_DQS_DP<5>";
%"TAP"
"6","(-5575,900)","0","mstr_standard","I10";
;
HDL_TAP"TRUE"
BODY_TYPE"PLUMBING"
CDS_LIB"mstr_standard";
"B \NAC \NWC"11;
"S \NAC"
BN"1"21;
%"TAP"
"6","(-2850,1500)","2","mstr_standard","I100";
;
HDL_TAP"TRUE"
BODY_TYPE"PLUMBING"
CDS_LIB"mstr_standard";
"B \NAC \NWC"4;
"S \NAC"
BN"1"114;
%"TAP"
"6","(-2850,1550)","2","mstr_standard","I101";
;
HDL_TAP"TRUE"
BODY_TYPE"PLUMBING"
CDS_LIB"mstr_standard";
"B \NAC \NWC"4;
"S \NAC"
BN"2"113;
%"TAP"
"6","(-2850,1600)","2","mstr_standard","I102";
;
HDL_TAP"TRUE"
BODY_TYPE"PLUMBING"
CDS_LIB"mstr_standard";
"B \NAC \NWC"4;
"S \NAC"
BN"3"112;
%"TAP"
"6","(-2850,1700)","2","mstr_standard","I103";
;
HDL_TAP"TRUE"
BODY_TYPE"PLUMBING"
CDS_LIB"mstr_standard";
"B \NAC \NWC"6;
"S \NAC"
BN"0"101;
%"TAP"
"6","(-2850,1750)","2","mstr_standard","I104";
;
HDL_TAP"TRUE"
BODY_TYPE"PLUMBING"
CDS_LIB"mstr_standard";
"B \NAC \NWC"6;
"S \NAC"
BN"1"100;
%"TAP"
"6","(-2850,1800)","2","mstr_standard","I105";
;
HDL_TAP"TRUE"
BODY_TYPE"PLUMBING"
CDS_LIB"mstr_standard";
"B \NAC \NWC"6;
"S \NAC"
BN"2"99;
%"TAP"
"6","(-2850,1850)","2","mstr_standard","I106";
;
HDL_TAP"TRUE"
BODY_TYPE"PLUMBING"
CDS_LIB"mstr_standard";
"B \NAC \NWC"6;
"S \NAC"
BN"3"98;
%"TAP"
"6","(-2850,1950)","2","mstr_standard","I107";
;
HDL_TAP"TRUE"
BODY_TYPE"PLUMBING"
CDS_LIB"mstr_standard";
"B \NAC \NWC"2;
"S \NAC"
BN"0"111;
%"TAP"
"6","(-2850,2050)","2","mstr_standard","I108";
;
HDL_TAP"TRUE"
BODY_TYPE"PLUMBING"
CDS_LIB"mstr_standard";
"B \NAC \NWC"2;
"S \NAC"
BN"2"157;
%"TAP"
"6","(-2850,2000)","2","mstr_standard","I109";
;
HDL_TAP"TRUE"
BODY_TYPE"PLUMBING"
CDS_LIB"mstr_standard";
"B \NAC \NWC"2;
"S \NAC"
BN"1"110;
%"TAP"
"6","(-5575,950)","0","mstr_standard","I11";
;
HDL_TAP"TRUE"
BODY_TYPE"PLUMBING"
CDS_LIB"mstr_standard";
"B \NAC \NWC"11;
"S \NAC"
BN"2"20;
%"TAP"
"6","(-2850,2100)","2","mstr_standard","I110";
;
HDL_TAP"TRUE"
BODY_TYPE"PLUMBING"
CDS_LIB"mstr_standard";
"B \NAC \NWC"2;
"S \NAC"
BN"3"156;
%"TAP"
"6","(-2850,2150)","2","mstr_standard","I111";
;
HDL_TAP"TRUE"
BODY_TYPE"PLUMBING"
CDS_LIB"mstr_standard";
"B \NAC \NWC"2;
"S \NAC"
BN"4"155;
%"TAP"
"6","(-2850,2200)","2","mstr_standard","I112";
;
HDL_TAP"TRUE"
BODY_TYPE"PLUMBING"
CDS_LIB"mstr_standard";
"B \NAC \NWC"2;
"S \NAC"
BN"5"154;
%"TAP"
"6","(-2850,2250)","2","mstr_standard","I113";
;
HDL_TAP"TRUE"
BODY_TYPE"PLUMBING"
CDS_LIB"mstr_standard";
"B \NAC \NWC"2;
"S \NAC"
BN"6"153;
%"TAP"
"6","(-2850,2300)","2","mstr_standard","I114";
;
HDL_TAP"TRUE"
BODY_TYPE"PLUMBING"
CDS_LIB"mstr_standard";
"B \NAC \NWC"2;
"S \NAC"
BN"7"152;
%"TAP"
"6","(-2850,2350)","2","mstr_standard","I115";
;
HDL_TAP"TRUE"
BODY_TYPE"PLUMBING"
CDS_LIB"mstr_standard";
"B \NAC \NWC"2;
"S \NAC"
BN"8"151;
%"TAP"
"6","(-2850,2400)","2","mstr_standard","I116";
;
HDL_TAP"TRUE"
BODY_TYPE"PLUMBING"
CDS_LIB"mstr_standard";
"B \NAC \NWC"2;
"S \NAC"
BN"9"150;
%"TAP"
"6","(-2850,2450)","2","mstr_standard","I117";
;
HDL_TAP"TRUE"
BODY_TYPE"PLUMBING"
CDS_LIB"mstr_standard";
"B \NAC \NWC"2;
"S \NAC"
BN"10"149;
%"TAP"
"6","(-2850,2500)","2","mstr_standard","I118";
;
HDL_TAP"TRUE"
BODY_TYPE"PLUMBING"
CDS_LIB"mstr_standard";
"B \NAC \NWC"2;
"S \NAC"
BN"11"148;
%"TAP"
"6","(-2850,2550)","2","mstr_standard","I119";
;
HDL_TAP"TRUE"
BODY_TYPE"PLUMBING"
CDS_LIB"mstr_standard";
"B \NAC \NWC"2;
"S \NAC"
BN"12"147;
%"TAP"
"6","(-5575,1000)","0","mstr_standard","I12";
;
HDL_TAP"TRUE"
BODY_TYPE"PLUMBING"
CDS_LIB"mstr_standard";
"B \NAC \NWC"11;
"S \NAC"
BN"3"19;
%"TAP"
"6","(-2850,2600)","2","mstr_standard","I120";
;
HDL_TAP"TRUE"
BODY_TYPE"PLUMBING"
CDS_LIB"mstr_standard";
"B \NAC \NWC"2;
"S \NAC"
BN"13"146;
%"TAP"
"6","(-2850,2650)","2","mstr_standard","I121";
;
HDL_TAP"TRUE"
BODY_TYPE"PLUMBING"
CDS_LIB"mstr_standard";
"B \NAC \NWC"2;
"S \NAC"
BN"14"145;
%"TAP"
"6","(-2850,2700)","2","mstr_standard","I122";
;
HDL_TAP"TRUE"
BODY_TYPE"PLUMBING"
CDS_LIB"mstr_standard";
"B \NAC \NWC"2;
"S \NAC"
BN"15"144;
%"TAP"
"6","(-2850,2750)","2","mstr_standard","I123";
;
HDL_TAP"TRUE"
BODY_TYPE"PLUMBING"
CDS_LIB"mstr_standard";
"B \NAC \NWC"2;
"S \NAC"
BN"16"143;
%"TAP"
"6","(-2850,2800)","2","mstr_standard","I124";
;
HDL_TAP"TRUE"
BODY_TYPE"PLUMBING"
CDS_LIB"mstr_standard";
"B \NAC \NWC"2;
"S \NAC"
BN"17"142;
%"TAP"
"6","(-2850,2950)","2","mstr_standard","I125";
;
HDL_TAP"TRUE"
BODY_TYPE"PLUMBING"
CDS_LIB"mstr_standard";
"B \NAC \NWC"3;
"S \NAC"
BN"1"135;
%"TAP"
"6","(-2850,2900)","2","mstr_standard","I126";
;
HDL_TAP"TRUE"
BODY_TYPE"PLUMBING"
CDS_LIB"mstr_standard";
"B \NAC \NWC"3;
"S \NAC"
BN"0"136;
%"TAP"
"6","(-2850,3000)","2","mstr_standard","I127";
;
HDL_TAP"TRUE"
BODY_TYPE"PLUMBING"
CDS_LIB"mstr_standard";
"B \NAC \NWC"3;
"S \NAC"
BN"2"134;
%"TAP"
"6","(-2850,3050)","2","mstr_standard","I128";
;
HDL_TAP"TRUE"
BODY_TYPE"PLUMBING"
CDS_LIB"mstr_standard";
"B \NAC \NWC"3;
"S \NAC"
BN"3"133;
%"TAP"
"6","(-2850,3100)","2","mstr_standard","I129";
;
HDL_TAP"TRUE"
BODY_TYPE"PLUMBING"
CDS_LIB"mstr_standard";
"B \NAC \NWC"3;
"S \NAC"
BN"4"132;
%"TAP"
"6","(-5575,1100)","0","mstr_standard","I13";
;
HDL_TAP"TRUE"
BODY_TYPE"PLUMBING"
CDS_LIB"mstr_standard";
"B \NAC \NWC"10;
"S \NAC"
BN"0"39;
%"TAP"
"6","(-2850,3150)","2","mstr_standard","I130";
;
HDL_TAP"TRUE"
BODY_TYPE"PLUMBING"
CDS_LIB"mstr_standard";
"B \NAC \NWC"3;
"S \NAC"
BN"5"131;
%"TAP"
"6","(-2850,3250)","2","mstr_standard","I131";
;
HDL_TAP"TRUE"
BODY_TYPE"PLUMBING"
CDS_LIB"mstr_standard";
"B \NAC \NWC"3;
"S \NAC"
BN"7"129;
%"TAP"
"6","(-2850,3200)","2","mstr_standard","I132";
;
HDL_TAP"TRUE"
BODY_TYPE"PLUMBING"
CDS_LIB"mstr_standard";
"B \NAC \NWC"3;
"S \NAC"
BN"6"130;
%"TAP"
"6","(-2850,3300)","2","mstr_standard","I133";
;
HDL_TAP"TRUE"
BODY_TYPE"PLUMBING"
CDS_LIB"mstr_standard";
"B \NAC \NWC"3;
"S \NAC"
BN"8"128;
%"TAP"
"6","(-2850,3350)","2","mstr_standard","I134";
;
HDL_TAP"TRUE"
BODY_TYPE"PLUMBING"
CDS_LIB"mstr_standard";
"B \NAC \NWC"3;
"S \NAC"
BN"9"127;
%"TAP"
"6","(-2850,3400)","2","mstr_standard","I135";
;
HDL_TAP"TRUE"
BODY_TYPE"PLUMBING"
CDS_LIB"mstr_standard";
"B \NAC \NWC"3;
"S \NAC"
BN"10"126;
%"TAP"
"6","(-2850,3500)","2","mstr_standard","I136";
;
HDL_TAP"TRUE"
BODY_TYPE"PLUMBING"
CDS_LIB"mstr_standard";
"B \NAC \NWC"3;
"S \NAC"
BN"12"124;
%"TAP"
"6","(-2850,3450)","2","mstr_standard","I137";
;
HDL_TAP"TRUE"
BODY_TYPE"PLUMBING"
CDS_LIB"mstr_standard";
"B \NAC \NWC"3;
"S \NAC"
BN"11"125;
%"TAP"
"6","(-2850,3550)","2","mstr_standard","I138";
;
HDL_TAP"TRUE"
BODY_TYPE"PLUMBING"
CDS_LIB"mstr_standard";
"B \NAC \NWC"3;
"S \NAC"
BN"13"123;
%"TAP"
"6","(-2850,3650)","2","mstr_standard","I139";
;
HDL_TAP"TRUE"
BODY_TYPE"PLUMBING"
CDS_LIB"mstr_standard";
"B \NAC \NWC"3;
"S \NAC"
BN"15"121;
%"TAP"
"6","(-5575,1150)","0","mstr_standard","I14";
;
HDL_TAP"TRUE"
BODY_TYPE"PLUMBING"
CDS_LIB"mstr_standard";
"B \NAC \NWC"10;
"S \NAC"
BN"1"38;
%"TAP"
"6","(-2850,3600)","2","mstr_standard","I140";
;
HDL_TAP"TRUE"
BODY_TYPE"PLUMBING"
CDS_LIB"mstr_standard";
"B \NAC \NWC"3;
"S \NAC"
BN"14"122;
%"TAP"
"6","(-2850,3750)","2","mstr_standard","I141";
;
HDL_TAP"TRUE"
BODY_TYPE"PLUMBING"
CDS_LIB"mstr_standard";
"B \NAC \NWC"3;
"S \NAC"
BN"17"119;
%"TAP"
"6","(-2850,3700)","2","mstr_standard","I142";
;
HDL_TAP"TRUE"
BODY_TYPE"PLUMBING"
CDS_LIB"mstr_standard";
"B \NAC \NWC"3;
"S \NAC"
BN"16"120;
%"TAP"
"6","(-2850,3900)","2","mstr_standard","I143";
;
HDL_TAP"TRUE"
BODY_TYPE"PLUMBING"
CDS_LIB"mstr_standard";
"B \NAC \NWC"1;
"S \NAC"
BN"1"140;
%"TAP"
"6","(-2850,3850)","2","mstr_standard","I144";
;
HDL_TAP"TRUE"
BODY_TYPE"PLUMBING"
CDS_LIB"mstr_standard";
"B \NAC \NWC"1;
"S \NAC"
BN"0"141;
%"TAP"
"6","(-2850,3950)","2","mstr_standard","I145";
;
HDL_TAP"TRUE"
BODY_TYPE"PLUMBING"
CDS_LIB"mstr_standard";
"B \NAC \NWC"1;
"S \NAC"
BN"2"139;
%"TAP"
"6","(-2850,4000)","2","mstr_standard","I146";
;
HDL_TAP"TRUE"
BODY_TYPE"PLUMBING"
CDS_LIB"mstr_standard";
"B \NAC \NWC"1;
"S \NAC"
BN"3"138;
%"TAP"
"6","(-5575,1200)","0","mstr_standard","I15";
;
HDL_TAP"TRUE"
BODY_TYPE"PLUMBING"
CDS_LIB"mstr_standard";
"B \NAC \NWC"10;
"S \NAC"
BN"2"37;
%"TAP"
"6","(-2850,4100)","2","mstr_standard","I157";
;
HDL_TAP"TRUE"
BODY_TYPE"PLUMBING"
CDS_LIB"mstr_standard";
"B \NAC \NWC"1;
"S \NAC"
BN"5"170;
%"TAP"
"6","(-2850,4050)","2","mstr_standard","I158";
;
HDL_TAP"TRUE"
BODY_TYPE"PLUMBING"
CDS_LIB"mstr_standard";
"B \NAC \NWC"1;
"S \NAC"
BN"4"137;
%"TAP"
"6","(-2850,4150)","2","mstr_standard","I159";
;
HDL_TAP"TRUE"
BODY_TYPE"PLUMBING"
CDS_LIB"mstr_standard";
"B \NAC \NWC"1;
"S \NAC"
BN"6"169;
%"TAP"
"6","(-5575,1300)","0","mstr_standard","I16";
;
HDL_TAP"TRUE"
BODY_TYPE"PLUMBING"
CDS_LIB"mstr_standard";
"B \NAC \NWC"10;
"S \NAC"
BN"4"35;
%"TAP"
"6","(-2850,4200)","2","mstr_standard","I160";
;
HDL_TAP"TRUE"
BODY_TYPE"PLUMBING"
CDS_LIB"mstr_standard";
"B \NAC \NWC"1;
"S \NAC"
BN"7"168;
%"TAP"
"6","(-2850,4250)","2","mstr_standard","I161";
;
HDL_TAP"TRUE"
BODY_TYPE"PLUMBING"
CDS_LIB"mstr_standard";
"B \NAC \NWC"1;
"S \NAC"
BN"8"167;
%"TAP"
"6","(-2850,4300)","2","mstr_standard","I162";
;
HDL_TAP"TRUE"
BODY_TYPE"PLUMBING"
CDS_LIB"mstr_standard";
"B \NAC \NWC"1;
"S \NAC"
BN"9"166;
%"TAP"
"6","(-2850,4350)","2","mstr_standard","I163";
;
HDL_TAP"TRUE"
BODY_TYPE"PLUMBING"
CDS_LIB"mstr_standard";
"B \NAC \NWC"1;
"S \NAC"
BN"10"165;
%"TAP"
"6","(-2850,4400)","2","mstr_standard","I164";
;
HDL_TAP"TRUE"
BODY_TYPE"PLUMBING"
CDS_LIB"mstr_standard";
"B \NAC \NWC"1;
"S \NAC"
BN"11"164;
%"TAP"
"6","(-2850,4450)","2","mstr_standard","I165";
;
HDL_TAP"TRUE"
BODY_TYPE"PLUMBING"
CDS_LIB"mstr_standard";
"B \NAC \NWC"1;
"S \NAC"
BN"12"163;
%"TAP"
"6","(-2850,4550)","2","mstr_standard","I166";
;
HDL_TAP"TRUE"
BODY_TYPE"PLUMBING"
CDS_LIB"mstr_standard";
"B \NAC \NWC"1;
"S \NAC"
BN"14"161;
%"TAP"
"6","(-2850,4500)","2","mstr_standard","I167";
;
HDL_TAP"TRUE"
BODY_TYPE"PLUMBING"
CDS_LIB"mstr_standard";
"B \NAC \NWC"1;
"S \NAC"
BN"13"162;
%"TAP"
"6","(-2850,4600)","2","mstr_standard","I168";
;
HDL_TAP"TRUE"
BODY_TYPE"PLUMBING"
CDS_LIB"mstr_standard";
"B \NAC \NWC"1;
"S \NAC"
BN"15"160;
%"TAP"
"6","(-2850,4650)","2","mstr_standard","I169";
;
HDL_TAP"TRUE"
BODY_TYPE"PLUMBING"
CDS_LIB"mstr_standard";
"B \NAC \NWC"1;
"S \NAC"
BN"16"159;
%"TAP"
"6","(-5575,1250)","0","mstr_standard","I17";
;
HDL_TAP"TRUE"
BODY_TYPE"PLUMBING"
CDS_LIB"mstr_standard";
"B \NAC \NWC"10;
"S \NAC"
BN"3"36;
%"TAP"
"6","(-2850,4700)","2","mstr_standard","I170";
;
HDL_TAP"TRUE"
BODY_TYPE"PLUMBING"
CDS_LIB"mstr_standard";
"B \NAC \NWC"1;
"S \NAC"
BN"17"158;
%"SKX_EXT_B"
"5","(-4175,2600)","0","chpset_lib","I172";
;
CDS_SEC"5"
ROOM"CPU0"
CDS_LOCATION"U5D1"
SEC"5"
SEC_TYPE"BGA1"
CDS_LIB"chpset_lib"
PACK_TYPE"BGA1"
MATERIAL"IC"
PART_NUMBER"TBD"
LOCATION"U5D1";
"DDR2_PAR"
$PN"V53"116;
"DDR2_ODT<0>"
$PN"AA50"115;
"DDR2_ODT<1>"
$PN"AA48"114;
"DDR2_ODT<2>"
$PN"V49"113;
"DDR2_ODT<3>"
$PN"AB47"112;
"DDR2_MA<0>"
$PN"AB53"111;
"DDR2_MA<1>"
$PN"AE58"110;
"DDR2_MA<2>"
$PN"AD57"157;
"DDR2_MA<3>"
$PN"W58"156;
"DDR2_MA<4>"
$PN"AA58"155;
"DDR2_MA<5>"
$PN"V59"154;
"DDR2_MA<6>"
$PN"AB59"153;
"DDR2_MA<7>"
$PN"AE60"152;
"DDR2_MA<8>"
$PN"AD59"151;
"DDR2_MA<9>"
$PN"AG58"150;
"DDR2_MA<10>"
$PN"AD55"149;
"DDR2_MA<11>"
$PN"AG60"148;
"DDR2_MA<12>"
$PN"AG62"147;
"DDR2_MA<13>"
$PN"AD53"146;
"DDR2_MA<14>"
$PN"W50"145;
"DDR2_MA<15>"
$PN"AE54"144;
"DDR2_MA<16>"
$PN"AA52"143;
"DDR2_MA<17>"
$PN"AC46"142;
"DDR2_ECC<0>"
$PN"AU72"39;
"DDR2_ECC<1>"
$PN"BA72"38;
"DDR2_ECC<2>"
$PN"AV69"37;
"DDR2_ECC<3>"
$PN"AY69"36;
"DDR2_ECC<4>"
$PN"AV73"35;
"DDR2_ECC<5>"
$PN"AY73"34;
"DDR2_ECC<6>"
$PN"AU70"33;
"DDR2_ECC<7>"
$PN"BA70"32;
"DDR2_DQS_DP<0>"
$PN"AM75"141;
"DDR2_DQS_DP<1>"
$PN"AB75"140;
"DDR2_DQS_DP<2>"
$PN"W70"139;
"DDR2_DQS_DP<3>"
$PN"AR66"138;
"DDR2_DQS_DP<4>"
$PN"Y39"137;
"DDR2_DQS_DP<5>"
$PN"Y33"170;
"DDR2_DQS_DP<6>"
$PN"AG30"169;
"DDR2_DQS_DP<7>"
$PN"AG24"168;
"DDR2_DQS_DP<8>"
$PN"AY71"167;
"DDR2_DQS_DP<9>"
$PN"AN76"166;
"DDR2_DQS_DP<10>"
$PN"AC76"165;
"DDR2_DQS_DP<11>"
$PN"V71"164;
"DDR2_DQS_DP<12>"
$PN"AN66"163;
"DDR2_DQS_DP<13>"
$PN"V39"162;
"DDR2_DQS_DP<14>"
$PN"V33"161;
"DDR2_DQS_DP<15>"
$PN"AE30"160;
"DDR2_DQS_DP<16>"
$PN"AE24"159;
"DDR2_DQS_DP<17>"
$PN"AV71"158;
"DDR2_DQS_DN<0>"
$PN"AL74"136;
"DDR2_DQS_DN<1>"
$PN"AA74"135;
"DDR2_DQS_DN<2>"
$PN"Y69"134;
"DDR2_DQS_DN<3>"
$PN"AU66"133;
"DDR2_DQS_DN<4>"
$PN"AB39"132;
"DDR2_DQS_DN<5>"
$PN"AB33"131;
"DDR2_DQS_DN<6>"
$PN"AJ30"130;
"DDR2_DQS_DN<7>"
$PN"AJ24"129;
"DDR2_DQS_DN<8>"
$PN"BB71"128;
"DDR2_DQS_DN<9>"
$PN"AP77"127;
"DDR2_DQS_DN<10>"
$PN"AD77"126;
"DDR2_DQS_DN<11>"
$PN"U72"125;
"DDR2_DQS_DN<12>"
$PN"AL66"124;
"DDR2_DQS_DN<13>"
$PN"T39"123;
"DDR2_DQS_DN<14>"
$PN"T33"122;
"DDR2_DQS_DN<15>"
$PN"AC30"121;
"DDR2_DQS_DN<16>"
$PN"AC24"120;
"DDR2_DQS_DN<17>"
$PN"AT71"119;
"DDR2_DQ<0>"
$PN"AR76"31;
"DDR2_DQ<1>"
$PN"AN74"30;
"DDR2_DQ<2>"
$PN"AK77"29;
"DDR2_DQ<3>"
$PN"AJ76"28;
"DDR2_DQ<4>"
$PN"AT75"13;
"DDR2_DQ<5>"
$PN"AR74"27;
"DDR2_DQ<6>"
$PN"AM77"26;
"DDR2_DQ<7>"
$PN"AK75"25;
"DDR2_DQ<8>"
$PN"AE76"24;
"DDR2_DQ<9>"
$PN"AC74"23;
"DDR2_DQ<10>"
$PN"Y77"79;
"DDR2_DQ<11>"
$PN"W76"78;
"DDR2_DQ<12>"
$PN"AF75"77;
"DDR2_DQ<13>"
$PN"AE74"76;
"DDR2_DQ<14>"
$PN"AB77"75;
"DDR2_DQ<15>"
$PN"Y75"74;
"DDR2_DQ<16>"
$PN"W72"73;
"DDR2_DQ<17>"
$PN"AA70"72;
"DDR2_DQ<18>"
$PN"R70"71;
"DDR2_DQ<19>"
$PN"T69"70;
"DDR2_DQ<20>"
$PN"AA72"69;
"DDR2_DQ<21>"
$PN"AB71"80;
"DDR2_DQ<22>"
$PN"T71"68;
"DDR2_DQ<23>"
$PN"V69"67;
"DDR2_DQ<24>"
$PN"AM67"66;
"DDR2_DQ<25>"
$PN"AT67"65;
"DDR2_DQ<26>"
$PN"AN64"64;
"DDR2_DQ<27>"
$PN"AR64"63;
"DDR2_DQ<28>"
$PN"AN68"62;
"DDR2_DQ<29>"
$PN"AR68"61;
"DDR2_DQ<30>"
$PN"AM65"60;
"DDR2_DQ<31>"
$PN"AT65"59;
"DDR2_DQ<32>"
$PN"U40"58;
"DDR2_DQ<33>"
$PN"AA40"57;
"DDR2_DQ<34>"
$PN"V37"56;
"DDR2_DQ<35>"
$PN"Y37"55;
"DDR2_DQ<36>"
$PN"V41"54;
"DDR2_DQ<37>"
$PN"Y41"53;
"DDR2_DQ<38>"
$PN"U38"52;
"DDR2_DQ<39>"
$PN"AA38"51;
"DDR2_DQ<40>"
$PN"U34"50;
"DDR2_DQ<41>"
$PN"AA34"49;
"DDR2_DQ<42>"
$PN"V31"48;
"DDR2_DQ<43>"
$PN"Y31"47;
"DDR2_DQ<44>"
$PN"V35"46;
"DDR2_DQ<45>"
$PN"Y35"45;
"DDR2_DQ<46>"
$PN"U32"44;
"DDR2_DQ<47>"
$PN"AA32"43;
"DDR2_DQ<48>"
$PN"AD31"42;
"DDR2_DQ<49>"
$PN"AH31"41;
"DDR2_DQ<50>"
$PN"AE28"40;
"DDR2_DQ<51>"
$PN"AG28"93;
"DDR2_DQ<52>"
$PN"AE32"92;
"DDR2_DQ<53>"
$PN"AG32"91;
"DDR2_DQ<54>"
$PN"AD29"90;
"DDR2_DQ<55>"
$PN"AH29"89;
"DDR2_DQ<56>"
$PN"AD25"88;
"DDR2_DQ<57>"
$PN"AH25"87;
"DDR2_DQ<58>"
$PN"AE22"86;
"DDR2_DQ<59>"
$PN"AG22"85;
"DDR2_DQ<60>"
$PN"AE26"84;
"DDR2_DQ<61>"
$PN"AG26"83;
"DDR2_DQ<62>"
$PN"AD23"82;
"DDR2_DQ<63>"
$PN"AH23"81;
"DDR2_CS_N<0>"
$PN"V51"109;
"DDR2_CS_N<1>"
$PN"AB49"108;
"DDR2_CS_N<2>"
$PN"W46"107;
"DDR2_CS_N<3>"
$PN"AA46"106;
"DDR2_CS_N<4>"
$PN"AB51"105;
"DDR2_CS_N<5>"
$PN"W48"104;
"DDR2_CS_N<6>"
$PN"T45"103;
"DDR2_CS_N<7>"
$PN"V45"102;
"DDR2_CLK_DP<0>"
$PN"AB55"22;
"DDR2_CLK_DP<1>"
$PN"V55"21;
"DDR2_CLK_DP<2>"
$PN"AB57"20;
"DDR2_CLK_DP<3>"
$PN"V57"19;
"DDR2_CLK_DN<0>"
$PN"AA54"18;
"DDR2_CLK_DN<1>"
$PN"W54"17;
"DDR2_CLK_DN<2>"
$PN"AA56"16;
"DDR2_CLK_DN<3>"
$PN"W56"15;
"DDR2_CKE<0>"
$PN"AA62"101;
"DDR2_CKE<1>"
$PN"AD63"100;
"DDR2_CKE<2>"
$PN"V63"99;
"DDR2_CKE<3>"
$PN"AB63"98;
"DDR2_CID<2>"
$PN"AB45"14;
"DDR2_BG<0>"
$PN"AA60"97;
"DDR2_BG<1>"
$PN"AE62"96;
"DDR2_BA<0>"
$PN"W52"95;
"DDR2_BA<1>"
$PN"AE56"94;
"DDR2_ALERT_N"
$PN"AD61"118;
"DDR2_ACT_N"
$PN"AB61"117;
%"TAP"
"6","(-5575,1350)","0","mstr_standard","I18";
;
HDL_TAP"TRUE"
BODY_TYPE"PLUMBING"
CDS_LIB"mstr_standard";
"B \NAC \NWC"10;
"S \NAC"
BN"5"34;
%"TAP"
"6","(-5575,1400)","0","mstr_standard","I19";
;
HDL_TAP"TRUE"
BODY_TYPE"PLUMBING"
CDS_LIB"mstr_standard";
"B \NAC \NWC"10;
"S \NAC"
BN"6"33;
%"TAP"
"6","(-5575,1450)","0","mstr_standard","I20";
;
HDL_TAP"TRUE"
BODY_TYPE"PLUMBING"
CDS_LIB"mstr_standard";
"B \NAC \NWC"10;
"S \NAC"
BN"7"32;
%"TAP"
"6","(-5575,1600)","0","mstr_standard","I21";
;
HDL_TAP"TRUE"
BODY_TYPE"PLUMBING"
CDS_LIB"mstr_standard";
"B \NAC \NWC"9;
"S \NAC"
BN"1"30;
%"TAP"
"6","(-5575,1550)","0","mstr_standard","I22";
;
HDL_TAP"TRUE"
BODY_TYPE"PLUMBING"
CDS_LIB"mstr_standard";
"B \NAC \NWC"9;
"S \NAC"
BN"0"31;
%"TAP"
"6","(-5575,1650)","0","mstr_standard","I23";
;
HDL_TAP"TRUE"
BODY_TYPE"PLUMBING"
CDS_LIB"mstr_standard";
"B \NAC \NWC"9;
"S \NAC"
BN"2"29;
%"TAP"
"6","(-5575,1700)","0","mstr_standard","I24";
;
HDL_TAP"TRUE"
BODY_TYPE"PLUMBING"
CDS_LIB"mstr_standard";
"B \NAC \NWC"9;
"S \NAC"
BN"3"28;
%"TAP"
"6","(-5575,1750)","0","mstr_standard","I25";
;
HDL_TAP"TRUE"
BODY_TYPE"PLUMBING"
CDS_LIB"mstr_standard";
"B \NAC \NWC"9;
"S \NAC"
BN"4"13;
%"TAP"
"6","(-5575,1800)","0","mstr_standard","I26";
;
HDL_TAP"TRUE"
BODY_TYPE"PLUMBING"
CDS_LIB"mstr_standard";
"B \NAC \NWC"9;
"S \NAC"
BN"5"27;
%"TAP"
"6","(-5575,1850)","0","mstr_standard","I27";
;
HDL_TAP"TRUE"
BODY_TYPE"PLUMBING"
CDS_LIB"mstr_standard";
"B \NAC \NWC"9;
"S \NAC"
BN"6"26;
%"TAP"
"6","(-5575,1900)","0","mstr_standard","I28";
;
HDL_TAP"TRUE"
BODY_TYPE"PLUMBING"
CDS_LIB"mstr_standard";
"B \NAC \NWC"9;
"S \NAC"
BN"7"25;
%"TAP"
"6","(-5575,1950)","0","mstr_standard","I29";
;
HDL_TAP"TRUE"
BODY_TYPE"PLUMBING"
CDS_LIB"mstr_standard";
"B \NAC \NWC"9;
"S \NAC"
BN"8"24;
%"TAP"
"6","(-5575,2100)","0","mstr_standard","I31";
;
HDL_TAP"TRUE"
BODY_TYPE"PLUMBING"
CDS_LIB"mstr_standard";
"B \NAC \NWC"9;
"S \NAC"
BN"11"78;
%"TAP"
"6","(-5575,2050)","0","mstr_standard","I32";
;
HDL_TAP"TRUE"
BODY_TYPE"PLUMBING"
CDS_LIB"mstr_standard";
"B \NAC \NWC"9;
"S \NAC"
BN"10"79;
%"TAP"
"6","(-5575,2000)","0","mstr_standard","I33";
;
HDL_TAP"TRUE"
BODY_TYPE"PLUMBING"
CDS_LIB"mstr_standard";
"B \NAC \NWC"9;
"S \NAC"
BN"9"23;
%"TAP"
"6","(-5575,2150)","0","mstr_standard","I34";
;
HDL_TAP"TRUE"
BODY_TYPE"PLUMBING"
CDS_LIB"mstr_standard";
"B \NAC \NWC"9;
"S \NAC"
BN"12"77;
%"TAP"
"6","(-5575,2200)","0","mstr_standard","I35";
;
HDL_TAP"TRUE"
BODY_TYPE"PLUMBING"
CDS_LIB"mstr_standard";
"B \NAC \NWC"9;
"S \NAC"
BN"13"76;
%"TAP"
"6","(-5575,2250)","0","mstr_standard","I36";
;
HDL_TAP"TRUE"
BODY_TYPE"PLUMBING"
CDS_LIB"mstr_standard";
"B \NAC \NWC"9;
"S \NAC"
BN"14"75;
%"TAP"
"6","(-5575,2300)","0","mstr_standard","I37";
;
HDL_TAP"TRUE"
BODY_TYPE"PLUMBING"
CDS_LIB"mstr_standard";
"B \NAC \NWC"9;
"S \NAC"
BN"15"74;
%"TAP"
"6","(-5575,2350)","0","mstr_standard","I38";
;
HDL_TAP"TRUE"
BODY_TYPE"PLUMBING"
CDS_LIB"mstr_standard";
"B \NAC \NWC"9;
"S \NAC"
BN"16"73;
%"TAP"
"6","(-5575,2400)","0","mstr_standard","I39";
;
HDL_TAP"TRUE"
BODY_TYPE"PLUMBING"
CDS_LIB"mstr_standard";
"B \NAC \NWC"9;
"S \NAC"
BN"17"72;
%"TAP"
"6","(-5575,2450)","0","mstr_standard","I40";
;
HDL_TAP"TRUE"
BODY_TYPE"PLUMBING"
CDS_LIB"mstr_standard";
"B \NAC \NWC"9;
"S \NAC"
BN"18"71;
%"TAP"
"6","(-5575,2500)","0","mstr_standard","I41";
;
HDL_TAP"TRUE"
BODY_TYPE"PLUMBING"
CDS_LIB"mstr_standard";
"B \NAC \NWC"9;
"S \NAC"
BN"19"70;
%"TAP"
"6","(-5575,2600)","0","mstr_standard","I42";
;
HDL_TAP"TRUE"
BODY_TYPE"PLUMBING"
CDS_LIB"mstr_standard";
"B \NAC \NWC"9;
"S \NAC"
BN"21"80;
%"TAP"
"6","(-5575,2550)","0","mstr_standard","I43";
;
HDL_TAP"TRUE"
BODY_TYPE"PLUMBING"
CDS_LIB"mstr_standard";
"B \NAC \NWC"9;
"S \NAC"
BN"20"69;
%"TAP"
"6","(-5575,2650)","0","mstr_standard","I44";
;
HDL_TAP"TRUE"
BODY_TYPE"PLUMBING"
CDS_LIB"mstr_standard";
"B \NAC \NWC"9;
"S \NAC"
BN"22"68;
%"TAP"
"6","(-5575,2700)","0","mstr_standard","I45";
;
HDL_TAP"TRUE"
BODY_TYPE"PLUMBING"
CDS_LIB"mstr_standard";
"B \NAC \NWC"9;
"S \NAC"
BN"23"67;
%"TAP"
"6","(-5575,2750)","0","mstr_standard","I46";
;
HDL_TAP"TRUE"
BODY_TYPE"PLUMBING"
CDS_LIB"mstr_standard";
"B \NAC \NWC"9;
"S \NAC"
BN"24"66;
%"TAP"
"6","(-5575,2850)","0","mstr_standard","I47";
;
HDL_TAP"TRUE"
BODY_TYPE"PLUMBING"
CDS_LIB"mstr_standard";
"B \NAC \NWC"9;
"S \NAC"
BN"26"64;
%"TAP"
"6","(-5575,2800)","0","mstr_standard","I48";
;
HDL_TAP"TRUE"
BODY_TYPE"PLUMBING"
CDS_LIB"mstr_standard";
"B \NAC \NWC"9;
"S \NAC"
BN"25"65;
%"TAP"
"6","(-5575,2900)","0","mstr_standard","I49";
;
HDL_TAP"TRUE"
BODY_TYPE"PLUMBING"
CDS_LIB"mstr_standard";
"B \NAC \NWC"9;
"S \NAC"
BN"27"63;
%"TAP"
"6","(-5575,650)","0","mstr_standard","I5";
;
HDL_TAP"TRUE"
BODY_TYPE"PLUMBING"
CDS_LIB"mstr_standard";
"B \NAC \NWC"12;
"S \NAC"
BN"0"18;
%"TAP"
"6","(-5575,2950)","0","mstr_standard","I50";
;
HDL_TAP"TRUE"
BODY_TYPE"PLUMBING"
CDS_LIB"mstr_standard";
"B \NAC \NWC"9;
"S \NAC"
BN"28"62;
%"TAP"
"6","(-5575,3000)","0","mstr_standard","I51";
;
HDL_TAP"TRUE"
BODY_TYPE"PLUMBING"
CDS_LIB"mstr_standard";
"B \NAC \NWC"9;
"S \NAC"
BN"29"61;
%"TAP"
"6","(-5575,3050)","0","mstr_standard","I52";
;
HDL_TAP"TRUE"
BODY_TYPE"PLUMBING"
CDS_LIB"mstr_standard";
"B \NAC \NWC"9;
"S \NAC"
BN"30"60;
%"TAP"
"6","(-5575,3100)","0","mstr_standard","I53";
;
HDL_TAP"TRUE"
BODY_TYPE"PLUMBING"
CDS_LIB"mstr_standard";
"B \NAC \NWC"9;
"S \NAC"
BN"31"59;
%"TAP"
"6","(-5575,3200)","0","mstr_standard","I54";
;
HDL_TAP"TRUE"
BODY_TYPE"PLUMBING"
CDS_LIB"mstr_standard";
"B \NAC \NWC"9;
"S \NAC"
BN"33"57;
%"TAP"
"6","(-5575,3250)","0","mstr_standard","I55";
;
HDL_TAP"TRUE"
BODY_TYPE"PLUMBING"
CDS_LIB"mstr_standard";
"B \NAC \NWC"9;
"S \NAC"
BN"34"56;
%"TAP"
"6","(-5575,3150)","0","mstr_standard","I56";
;
HDL_TAP"TRUE"
BODY_TYPE"PLUMBING"
CDS_LIB"mstr_standard";
"B \NAC \NWC"9;
"S \NAC"
BN"32"58;
%"TAP"
"6","(-5575,3350)","0","mstr_standard","I57";
;
HDL_TAP"TRUE"
BODY_TYPE"PLUMBING"
CDS_LIB"mstr_standard";
"B \NAC \NWC"9;
"S \NAC"
BN"36"54;
%"TAP"
"6","(-5575,3300)","0","mstr_standard","I58";
;
HDL_TAP"TRUE"
BODY_TYPE"PLUMBING"
CDS_LIB"mstr_standard";
"B \NAC \NWC"9;
"S \NAC"
BN"35"55;
%"TAP"
"6","(-5575,3400)","0","mstr_standard","I59";
;
HDL_TAP"TRUE"
BODY_TYPE"PLUMBING"
CDS_LIB"mstr_standard";
"B \NAC \NWC"9;
"S \NAC"
BN"37"53;
%"TAP"
"6","(-5575,700)","0","mstr_standard","I6";
;
HDL_TAP"TRUE"
BODY_TYPE"PLUMBING"
CDS_LIB"mstr_standard";
"B \NAC \NWC"12;
"S \NAC"
BN"1"17;
%"TAP"
"6","(-5575,3450)","0","mstr_standard","I60";
;
HDL_TAP"TRUE"
BODY_TYPE"PLUMBING"
CDS_LIB"mstr_standard";
"B \NAC \NWC"9;
"S \NAC"
BN"38"52;
%"TAP"
"6","(-5575,3500)","0","mstr_standard","I61";
;
HDL_TAP"TRUE"
BODY_TYPE"PLUMBING"
CDS_LIB"mstr_standard";
"B \NAC \NWC"9;
"S \NAC"
BN"39"51;
%"TAP"
"6","(-5575,3600)","0","mstr_standard","I62";
;
HDL_TAP"TRUE"
BODY_TYPE"PLUMBING"
CDS_LIB"mstr_standard";
"B \NAC \NWC"9;
"S \NAC"
BN"41"49;
%"TAP"
"6","(-5575,3550)","0","mstr_standard","I63";
;
HDL_TAP"TRUE"
BODY_TYPE"PLUMBING"
CDS_LIB"mstr_standard";
"B \NAC \NWC"9;
"S \NAC"
BN"40"50;
%"TAP"
"6","(-5575,3650)","0","mstr_standard","I64";
;
HDL_TAP"TRUE"
BODY_TYPE"PLUMBING"
CDS_LIB"mstr_standard";
"B \NAC \NWC"9;
"S \NAC"
BN"42"48;
%"TAP"
"6","(-5575,3700)","0","mstr_standard","I65";
;
HDL_TAP"TRUE"
BODY_TYPE"PLUMBING"
CDS_LIB"mstr_standard";
"B \NAC \NWC"9;
"S \NAC"
BN"43"47;
%"TAP"
"6","(-5575,3750)","0","mstr_standard","I66";
;
HDL_TAP"TRUE"
BODY_TYPE"PLUMBING"
CDS_LIB"mstr_standard";
"B \NAC \NWC"9;
"S \NAC"
BN"44"46;
%"TAP"
"6","(-5575,3800)","0","mstr_standard","I67";
;
HDL_TAP"TRUE"
BODY_TYPE"PLUMBING"
CDS_LIB"mstr_standard";
"B \NAC \NWC"9;
"S \NAC"
BN"45"45;
%"TAP"
"6","(-5575,3850)","0","mstr_standard","I68";
;
HDL_TAP"TRUE"
BODY_TYPE"PLUMBING"
CDS_LIB"mstr_standard";
"B \NAC \NWC"9;
"S \NAC"
BN"46"44;
%"TAP"
"6","(-5575,3900)","0","mstr_standard","I69";
;
HDL_TAP"TRUE"
BODY_TYPE"PLUMBING"
CDS_LIB"mstr_standard";
"B \NAC \NWC"9;
"S \NAC"
BN"47"43;
%"TAP"
"6","(-5575,750)","0","mstr_standard","I7";
;
HDL_TAP"TRUE"
BODY_TYPE"PLUMBING"
CDS_LIB"mstr_standard";
"B \NAC \NWC"12;
"S \NAC"
BN"2"16;
%"TAP"
"6","(-5575,3950)","0","mstr_standard","I70";
;
HDL_TAP"TRUE"
BODY_TYPE"PLUMBING"
CDS_LIB"mstr_standard";
"B \NAC \NWC"9;
"S \NAC"
BN"48"42;
%"TAP"
"6","(-5575,4000)","0","mstr_standard","I71";
;
HDL_TAP"TRUE"
BODY_TYPE"PLUMBING"
CDS_LIB"mstr_standard";
"B \NAC \NWC"9;
"S \NAC"
BN"49"41;
%"TAP"
"6","(-5575,4100)","0","mstr_standard","I73";
;
HDL_TAP"TRUE"
BODY_TYPE"PLUMBING"
CDS_LIB"mstr_standard";
"B \NAC \NWC"9;
"S \NAC"
BN"51"93;
%"TAP"
"6","(-5575,4050)","0","mstr_standard","I74";
;
HDL_TAP"TRUE"
BODY_TYPE"PLUMBING"
CDS_LIB"mstr_standard";
"B \NAC \NWC"9;
"S \NAC"
BN"50"40;
%"TAP"
"6","(-5575,4150)","0","mstr_standard","I75";
;
HDL_TAP"TRUE"
BODY_TYPE"PLUMBING"
CDS_LIB"mstr_standard";
"B \NAC \NWC"9;
"S \NAC"
BN"52"92;
%"TAP"
"6","(-5575,4200)","0","mstr_standard","I76";
;
HDL_TAP"TRUE"
BODY_TYPE"PLUMBING"
CDS_LIB"mstr_standard";
"B \NAC \NWC"9;
"S \NAC"
BN"53"91;
%"TAP"
"6","(-5575,4250)","0","mstr_standard","I77";
;
HDL_TAP"TRUE"
BODY_TYPE"PLUMBING"
CDS_LIB"mstr_standard";
"B \NAC \NWC"9;
"S \NAC"
BN"54"90;
%"TAP"
"6","(-5575,4300)","0","mstr_standard","I78";
;
HDL_TAP"TRUE"
BODY_TYPE"PLUMBING"
CDS_LIB"mstr_standard";
"B \NAC \NWC"9;
"S \NAC"
BN"55"89;
%"TAP"
"6","(-5575,4350)","0","mstr_standard","I79";
;
HDL_TAP"TRUE"
BODY_TYPE"PLUMBING"
CDS_LIB"mstr_standard";
"B \NAC \NWC"9;
"S \NAC"
BN"56"88;
%"TAP"
"6","(-5575,800)","0","mstr_standard","I8";
;
HDL_TAP"TRUE"
BODY_TYPE"PLUMBING"
CDS_LIB"mstr_standard";
"B \NAC \NWC"12;
"S \NAC"
BN"3"15;
%"TAP"
"6","(-5575,4400)","0","mstr_standard","I80";
;
HDL_TAP"TRUE"
BODY_TYPE"PLUMBING"
CDS_LIB"mstr_standard";
"B \NAC \NWC"9;
"S \NAC"
BN"57"87;
%"TAP"
"6","(-5575,4450)","0","mstr_standard","I81";
;
HDL_TAP"TRUE"
BODY_TYPE"PLUMBING"
CDS_LIB"mstr_standard";
"B \NAC \NWC"9;
"S \NAC"
BN"58"86;
%"TAP"
"6","(-5575,4500)","0","mstr_standard","I82";
;
HDL_TAP"TRUE"
BODY_TYPE"PLUMBING"
CDS_LIB"mstr_standard";
"B \NAC \NWC"9;
"S \NAC"
BN"59"85;
%"TAP"
"6","(-5575,4550)","0","mstr_standard","I83";
;
HDL_TAP"TRUE"
BODY_TYPE"PLUMBING"
CDS_LIB"mstr_standard";
"B \NAC \NWC"9;
"S \NAC"
BN"60"84;
%"TAP"
"6","(-5575,4600)","0","mstr_standard","I84";
;
HDL_TAP"TRUE"
BODY_TYPE"PLUMBING"
CDS_LIB"mstr_standard";
"B \NAC \NWC"9;
"S \NAC"
BN"61"83;
%"TAP"
"6","(-5575,4700)","0","mstr_standard","I85";
;
HDL_TAP"TRUE"
BODY_TYPE"PLUMBING"
CDS_LIB"mstr_standard";
"B \NAC \NWC"9;
"S \NAC"
BN"63"81;
%"TAP"
"6","(-5575,4650)","0","mstr_standard","I86";
;
HDL_TAP"TRUE"
BODY_TYPE"PLUMBING"
CDS_LIB"mstr_standard";
"B \NAC \NWC"9;
"S \NAC"
BN"62"82;
%"TAP"
"6","(-2850,750)","2","mstr_standard","I87";
;
HDL_TAP"TRUE"
BODY_TYPE"PLUMBING"
CDS_LIB"mstr_standard";
"B \NAC \NWC"8;
"S \NAC"
BN"0"95;
%"TAP"
"6","(-2850,800)","2","mstr_standard","I88";
;
HDL_TAP"TRUE"
BODY_TYPE"PLUMBING"
CDS_LIB"mstr_standard";
"B \NAC \NWC"8;
"S \NAC"
BN"1"94;
%"TAP"
"6","(-2850,850)","2","mstr_standard","I89";
;
HDL_TAP"TRUE"
BODY_TYPE"PLUMBING"
CDS_LIB"mstr_standard";
"B \NAC \NWC"7;
"S \NAC"
BN"0"97;
%"TAP"
"6","(-5575,850)","0","mstr_standard","I9";
;
HDL_TAP"TRUE"
BODY_TYPE"PLUMBING"
CDS_LIB"mstr_standard";
"B \NAC \NWC"11;
"S \NAC"
BN"0"22;
%"TAP"
"6","(-2850,900)","2","mstr_standard","I90";
;
HDL_TAP"TRUE"
BODY_TYPE"PLUMBING"
CDS_LIB"mstr_standard";
"B \NAC \NWC"7;
"S \NAC"
BN"1"96;
%"TAP"
"6","(-2850,1000)","2","mstr_standard","I91";
;
HDL_TAP"TRUE"
BODY_TYPE"PLUMBING"
CDS_LIB"mstr_standard";
"B \NAC \NWC"5;
"S \NAC"
BN"0"109;
%"TAP"
"6","(-2850,1100)","2","mstr_standard","I92";
;
HDL_TAP"TRUE"
BODY_TYPE"PLUMBING"
CDS_LIB"mstr_standard";
"B \NAC \NWC"5;
"S \NAC"
BN"2"107;
%"TAP"
"6","(-2850,1050)","2","mstr_standard","I93";
;
HDL_TAP"TRUE"
BODY_TYPE"PLUMBING"
CDS_LIB"mstr_standard";
"B \NAC \NWC"5;
"S \NAC"
BN"1"108;
%"TAP"
"6","(-2850,1200)","2","mstr_standard","I94";
;
HDL_TAP"TRUE"
BODY_TYPE"PLUMBING"
CDS_LIB"mstr_standard";
"B \NAC \NWC"5;
"S \NAC"
BN"4"105;
%"TAP"
"6","(-2850,1150)","2","mstr_standard","I95";
;
HDL_TAP"TRUE"
BODY_TYPE"PLUMBING"
CDS_LIB"mstr_standard";
"B \NAC \NWC"5;
"S \NAC"
BN"3"106;
%"TAP"
"6","(-2850,1250)","2","mstr_standard","I96";
;
HDL_TAP"TRUE"
BODY_TYPE"PLUMBING"
CDS_LIB"mstr_standard";
"B \NAC \NWC"5;
"S \NAC"
BN"5"104;
%"TAP"
"6","(-2850,1300)","2","mstr_standard","I97";
;
HDL_TAP"TRUE"
BODY_TYPE"PLUMBING"
CDS_LIB"mstr_standard";
"B \NAC \NWC"5;
"S \NAC"
BN"6"103;
%"TAP"
"6","(-2850,1350)","2","mstr_standard","I98";
;
HDL_TAP"TRUE"
BODY_TYPE"PLUMBING"
CDS_LIB"mstr_standard";
"B \NAC \NWC"5;
"S \NAC"
BN"7"102;
%"TAP"
"6","(-2850,1450)","2","mstr_standard","I99";
;
HDL_TAP"TRUE"
BODY_TYPE"PLUMBING"
CDS_LIB"mstr_standard";
"B \NAC \NWC"4;
"S \NAC"
BN"0"115;
END.
